(kicad_pcb
	(version 20260206)
	(generator "pcbnew")
	(generator_version "10.0")
	(general
		(thickness 1.6)
		(legacy_teardrops no)
	)
	(paper "A4")
	(title_block
		(title "04192023_DAF0TMB3IC0_F0TG_MB_C_brd_V02_OCP.brd")
		(comment 1 "Grand Teton / footprints 4204-4210 of 8354")
	)
	(layers
		(0 "F.Cu" signal "TOP")
		(4 "In1.Cu" signal "GND")
		(6 "In2.Cu" signal "IN1")
		(8 "In3.Cu" signal "GND1")
		(10 "In4.Cu" signal "IN2")
		(12 "In5.Cu" signal "GND2")
		(14 "In6.Cu" signal "IN3")
		(16 "In7.Cu" signal "GND3")
		(18 "In8.Cu" signal "VCC")
		(20 "In9.Cu" signal "VCC1")
		(22 "In10.Cu" signal "GND4")
		(24 "In11.Cu" signal "IN4")
		(26 "In12.Cu" signal "GND5")
		(28 "In13.Cu" signal "IN5")
		(30 "In14.Cu" signal "GND6")
		(32 "In15.Cu" signal "IN6")
		(34 "In16.Cu" signal "GND7")
		(2 "B.Cu" signal "BOTTOM")
		(9 "F.Adhes" user "F.Adhesive")
		(11 "B.Adhes" user "B.Adhesive")
		(13 "F.Paste" user "Package Geometry/Pastemask Top")
		(15 "B.Paste" user "Package Geometry/Pastemask Bottom")
		(5 "F.SilkS" user "Ref Des/Silkscreen Top")
		(7 "B.SilkS" user "Ref Des/Silkscreen Bottom")
		(1 "F.Mask" user "Board Geometry/Soldermask Top")
		(3 "B.Mask" user "Board Geometry/Soldermask Bottom")
		(17 "Dwgs.User" user "User.Drawings")
		(19 "Cmts.User" user "User.Comments")
		(21 "Eco1.User" user "User.Eco1")
		(23 "Eco2.User" user "User.Eco2")
		(25 "Edge.Cuts" user "Board Geometry/Outline")
		(27 "Margin" user)
		(31 "F.CrtYd" user "Package Geometry/Place Bound Top")
		(29 "B.CrtYd" user "Package Geometry/Place Bound Bottom")
		(35 "F.Fab" user "Ref Des/Assembly Top")
		(33 "B.Fab" user "Ref Des/Assembly Bottom")
	)
	(footprint ""
		(layer "F.Cu")
		(at 208.894426 -109.561376 180)
		(property "Reference" "R6055"
			(at 0 0 180)
			(layer "F.SilkS")
			(hide yes)
			(effects
				(font
					(size 1.27 1.27)
				)
			)
		)
		(property "Value" ""
			(at 0 0 180)
			(layer "F.Fab")
			(effects
				(font
					(size 1.27 1.27)
				)
			)
		)
		(duplicate_pad_numbers_are_jumpers no)
		(fp_line
			(start 0.7874 0.4064)
			(end -0.7874 0.4064)
			(stroke
				(width 0.1524)
				(type default)
			)
			(layer "F.SilkS")
		)
		(fp_line
			(start 0.7874 -0.4064)
			(end 0.7874 0.4064)
			(stroke
				(width 0.1524)
				(type default)
			)
			(layer "F.SilkS")
		)
		(fp_line
			(start -0.7874 0.4064)
			(end -0.7874 -0.4064)
			(stroke
				(width 0.1524)
				(type default)
			)
			(layer "F.SilkS")
		)
		(fp_line
			(start -0.7874 -0.4064)
			(end 0.7874 -0.4064)
			(stroke
				(width 0.1524)
				(type default)
			)
			(layer "F.SilkS")
		)
		(fp_line
			(start 0.67945 0.3048)
			(end 0.120396 0.3048)
			(stroke
				(width 0.1)
				(type default)
			)
			(layer "F.Fab")
		)
		(fp_line
			(start 0.67945 -0.3048)
			(end 0.67945 0.3048)
			(stroke
				(width 0.1)
				(type default)
			)
			(layer "F.Fab")
		)
		(fp_line
			(start 0.12065 -0.2794)
			(end 0.12065 -0.3048)
			(stroke
				(width 0.1)
				(type default)
			)
			(layer "F.Fab")
		)
		(fp_line
			(start 0.12065 -0.3048)
			(end 0.67945 -0.3048)
			(stroke
				(width 0.1)
				(type default)
			)
			(layer "F.Fab")
		)
		(fp_line
			(start 0.120396 0.3048)
			(end 0.120396 0.2794)
			(stroke
				(width 0.1)
				(type default)
			)
			(layer "F.Fab")
		)
		(fp_line
			(start 0.120396 0.2794)
			(end -0.12065 0.2794)
			(stroke
				(width 0.1)
				(type default)
			)
			(layer "F.Fab")
		)
		(fp_line
			(start -0.12065 0.3048)
			(end -0.67945 0.3048)
			(stroke
				(width 0.1)
				(type default)
			)
			(layer "F.Fab")
		)
		(fp_line
			(start -0.12065 0.2794)
			(end -0.12065 0.3048)
			(stroke
				(width 0.1)
				(type default)
			)
			(layer "F.Fab")
		)
		(fp_line
			(start -0.12065 -0.2794)
			(end 0.12065 -0.2794)
			(stroke
				(width 0.1)
				(type default)
			)
			(layer "F.Fab")
		)
		(fp_line
			(start -0.12065 -0.305054)
			(end -0.12065 -0.2794)
			(stroke
				(width 0.1)
				(type default)
			)
			(layer "F.Fab")
		)
		(fp_line
			(start -0.67945 0.3048)
			(end -0.67945 -0.305054)
			(stroke
				(width 0.1)
				(type default)
			)
			(layer "F.Fab")
		)
		(fp_line
			(start -0.67945 -0.305054)
			(end -0.12065 -0.305054)
			(stroke
				(width 0.1)
				(type default)
			)
			(layer "F.Fab")
		)
		(pad "1" smd circle
			(at -0.40005 0 180)
			(size 0 0)
			(layers "F.Cu" "F.Mask" "F.Paste")
			(net "HP_LVC3_SCM_HSC_PWRGD")
		)
		(pad "2" smd circle
			(at 0.40005 0 180)
			(size 0 0)
			(layers "F.Cu" "F.Mask" "F.Paste")
			(net "P12V_SCM_PWRGD_R")
		)
	)
	(footprint ""
		(layer "F.Cu")
		(at 108.839 -415.417 -90)
		(property "Reference" "R560"
			(at 0 0 270)
			(layer "F.SilkS")
			(hide yes)
			(effects
				(font
					(size 1.27 1.27)
				)
			)
		)
		(property "Value" ""
			(at 0 0 270)
			(layer "F.Fab")
			(effects
				(font
					(size 1.27 1.27)
				)
			)
		)
		(duplicate_pad_numbers_are_jumpers no)
		(fp_line
			(start -0.7874 0.4064)
			(end -0.7874 -0.4064)
			(stroke
				(width 0.1524)
				(type default)
			)
			(layer "F.SilkS")
		)
		(fp_line
			(start 0.7874 0.4064)
			(end -0.7874 0.4064)
			(stroke
				(width 0.1524)
				(type default)
			)
			(layer "F.SilkS")
		)
		(fp_line
			(start -0.7874 -0.4064)
			(end 0.7874 -0.4064)
			(stroke
				(width 0.1524)
				(type default)
			)
			(layer "F.SilkS")
		)
		(fp_line
			(start 0.7874 -0.4064)
			(end 0.7874 0.4064)
			(stroke
				(width 0.1524)
				(type default)
			)
			(layer "F.SilkS")
		)
		(fp_line
			(start -0.67945 0.3048)
			(end -0.67945 -0.305054)
			(stroke
				(width 0.1)
				(type default)
			)
			(layer "F.Fab")
		)
		(fp_line
			(start -0.12065 0.3048)
			(end -0.67945 0.3048)
			(stroke
				(width 0.1)
				(type default)
			)
			(layer "F.Fab")
		)
		(fp_line
			(start 0.120396 0.3048)
			(end 0.120396 0.2794)
			(stroke
				(width 0.1)
				(type default)
			)
			(layer "F.Fab")
		)
		(fp_line
			(start 0.67945 0.3048)
			(end 0.120396 0.3048)
			(stroke
				(width 0.1)
				(type default)
			)
			(layer "F.Fab")
		)
		(fp_line
			(start -0.12065 0.2794)
			(end -0.12065 0.3048)
			(stroke
				(width 0.1)
				(type default)
			)
			(layer "F.Fab")
		)
		(fp_line
			(start 0.120396 0.2794)
			(end -0.12065 0.2794)
			(stroke
				(width 0.1)
				(type default)
			)
			(layer "F.Fab")
		)
		(fp_line
			(start -0.12065 -0.2794)
			(end 0.12065 -0.2794)
			(stroke
				(width 0.1)
				(type default)
			)
			(layer "F.Fab")
		)
		(fp_line
			(start 0.12065 -0.2794)
			(end 0.12065 -0.3048)
			(stroke
				(width 0.1)
				(type default)
			)
			(layer "F.Fab")
		)
		(fp_line
			(start 0.12065 -0.3048)
			(end 0.67945 -0.3048)
			(stroke
				(width 0.1)
				(type default)
			)
			(layer "F.Fab")
		)
		(fp_line
			(start 0.67945 -0.3048)
			(end 0.67945 0.3048)
			(stroke
				(width 0.1)
				(type default)
			)
			(layer "F.Fab")
		)
		(fp_line
			(start -0.67945 -0.305054)
			(end -0.12065 -0.305054)
			(stroke
				(width 0.1)
				(type default)
			)
			(layer "F.Fab")
		)
		(fp_line
			(start -0.12065 -0.305054)
			(end -0.12065 -0.2794)
			(stroke
				(width 0.1)
				(type default)
			)
			(layer "F.Fab")
		)
		(pad "1" smd circle
			(at -0.40005 0 270)
			(size 0 0)
			(layers "F.Cu" "F.Mask" "F.Paste")
			(net "P3V3_AUX")
		)
		(pad "2" smd circle
			(at 0.40005 0 270)
			(size 0 0)
			(layers "F.Cu" "F.Mask" "F.Paste")
			(net "FM_9ZXL045_P1_DEV_EN")
		)
	)
	(footprint ""
		(layer "F.Cu")
		(at 129.483104 -51.410616)
		(property "Reference" "R6109"
			(at 0 0 0)
			(layer "F.SilkS")
			(hide yes)
			(effects
				(font
					(size 1.27 1.27)
				)
			)
		)
		(property "Value" ""
			(at 0 0 0)
			(layer "F.Fab")
			(effects
				(font
					(size 1.27 1.27)
				)
			)
		)
		(duplicate_pad_numbers_are_jumpers no)
		(fp_line
			(start -0.7874 -0.4064)
			(end 0.7874 -0.4064)
			(stroke
				(width 0.1524)
				(type default)
			)
			(layer "F.SilkS")
		)
		(fp_line
			(start -0.7874 0.4064)
			(end -0.7874 -0.4064)
			(stroke
				(width 0.1524)
				(type default)
			)
			(layer "F.SilkS")
		)
		(fp_line
			(start 0.7874 -0.4064)
			(end 0.7874 0.4064)
			(stroke
				(width 0.1524)
				(type default)
			)
			(layer "F.SilkS")
		)
		(fp_line
			(start 0.7874 0.4064)
			(end -0.7874 0.4064)
			(stroke
				(width 0.1524)
				(type default)
			)
			(layer "F.SilkS")
		)
		(fp_line
			(start -0.67945 -0.305054)
			(end -0.12065 -0.305054)
			(stroke
				(width 0.1)
				(type default)
			)
			(layer "F.Fab")
		)
		(fp_line
			(start -0.67945 0.3048)
			(end -0.67945 -0.305054)
			(stroke
				(width 0.1)
				(type default)
			)
			(layer "F.Fab")
		)
		(fp_line
			(start -0.12065 -0.305054)
			(end -0.12065 -0.2794)
			(stroke
				(width 0.1)
				(type default)
			)
			(layer "F.Fab")
		)
		(fp_line
			(start -0.12065 -0.2794)
			(end 0.12065 -0.2794)
			(stroke
				(width 0.1)
				(type default)
			)
			(layer "F.Fab")
		)
		(fp_line
			(start -0.12065 0.2794)
			(end -0.12065 0.3048)
			(stroke
				(width 0.1)
				(type default)
			)
			(layer "F.Fab")
		)
		(fp_line
			(start -0.12065 0.3048)
			(end -0.67945 0.3048)
			(stroke
				(width 0.1)
				(type default)
			)
			(layer "F.Fab")
		)
		(fp_line
			(start 0.120396 0.2794)
			(end -0.12065 0.2794)
			(stroke
				(width 0.1)
				(type default)
			)
			(layer "F.Fab")
		)
		(fp_line
			(start 0.120396 0.3048)
			(end 0.120396 0.2794)
			(stroke
				(width 0.1)
				(type default)
			)
			(layer "F.Fab")
		)
		(fp_line
			(start 0.12065 -0.3048)
			(end 0.67945 -0.3048)
			(stroke
				(width 0.1)
				(type default)
			)
			(layer "F.Fab")
		)
		(fp_line
			(start 0.12065 -0.2794)
			(end 0.12065 -0.3048)
			(stroke
				(width 0.1)
				(type default)
			)
			(layer "F.Fab")
		)
		(fp_line
			(start 0.67945 -0.3048)
			(end 0.67945 0.3048)
			(stroke
				(width 0.1)
				(type default)
			)
			(layer "F.Fab")
		)
		(fp_line
			(start 0.67945 0.3048)
			(end 0.120396 0.3048)
			(stroke
				(width 0.1)
				(type default)
			)
			(layer "F.Fab")
		)
		(pad "1" smd circle
			(at -0.40005 0)
			(size 0 0)
			(layers "F.Cu" "F.Mask" "F.Paste")
			(net "JTAG_TDO")
		)
		(pad "2" smd circle
			(at 0.40005 0)
			(size 0 0)
			(layers "F.Cu" "F.Mask" "F.Paste")
			(net "JTAG_TDO_R")
		)
	)
	(footprint ""
		(layer "F.Cu")
		(at 132.603748 -165.848284 180)
		(property "Reference" "PL38"
			(at -0.737108 7.266178 0)
			(unlocked yes)
			(layer "F.SilkS")
			(effects
				(font
					(size 0.7874 0.5842)
					(thickness 0.1524)
				)
				(justify left)
			)
		)
		(property "Value" ""
			(at 0 0 180)
			(layer "F.Fab")
			(effects
				(font
					(size 1.27 1.27)
				)
			)
		)
		(duplicate_pad_numbers_are_jumpers no)
		(fp_line
			(start 3.750056 5.500116)
			(end 3.750056 -5.500116)
			(stroke
				(width 0.1524)
				(type default)
			)
			(layer "F.SilkS")
		)
		(fp_line
			(start 3.750056 -5.500116)
			(end 2.393442 -5.500116)
			(stroke
				(width 0.1524)
				(type default)
			)
			(layer "F.SilkS")
		)
		(fp_line
			(start 2.393442 5.500116)
			(end 3.750056 5.500116)
			(stroke
				(width 0.1524)
				(type default)
			)
			(layer "F.SilkS")
		)
		(fp_line
			(start -2.393442 5.500116)
			(end -3.750056 5.500116)
			(stroke
				(width 0.1524)
				(type default)
			)
			(layer "F.SilkS")
		)
		(fp_line
			(start -3.750056 5.500116)
			(end -3.750056 -5.500116)
			(stroke
				(width 0.1524)
				(type default)
			)
			(layer "F.SilkS")
		)
		(fp_line
			(start -3.750056 -5.500116)
			(end -2.393442 -5.500116)
			(stroke
				(width 0.1524)
				(type default)
			)
			(layer "F.SilkS")
		)
		(fp_poly
			(pts
				(xy -3.9116 -4.249928) (xy -4.556252 -3.927602) (xy -4.556252 -4.572254)
			)
			(stroke
				(width 0)
				(type default)
			)
			(fill yes)
			(layer "F.SilkS")
		)
		(fp_line
			(start 3.750056 5.500116)
			(end 3.750056 -5.500116)
			(stroke
				(width 0.1)
				(type default)
			)
			(layer "F.Fab")
		)
		(fp_line
			(start 3.750056 -5.500116)
			(end -3.750056 -5.500116)
			(stroke
				(width 0.1)
				(type default)
			)
			(layer "F.Fab")
		)
		(fp_line
			(start -3.750056 5.500116)
			(end 3.750056 5.500116)
			(stroke
				(width 0.1)
				(type default)
			)
			(layer "F.Fab")
		)
		(fp_line
			(start -3.750056 -5.500116)
			(end -3.750056 5.500116)
			(stroke
				(width 0.1)
				(type default)
			)
			(layer "F.Fab")
		)
		(fp_poly
			(pts
				(xy -4.9276 -4.757928) (xy -4.9276 -3.741928) (xy -3.9116 -4.249928)
			)
			(stroke
				(width 0)
				(type default)
			)
			(fill yes)
			(layer "F.Fab")
		)
		(pad "1" smd rect
			(at 0 -4.249928 90)
			(size 2.413 4.5212)
			(layers "F.Cu" "F.Mask" "F.Paste")
			(net "SW_PVDDCR_SOC_P1_SW3")
		)
		(pad "2" smd rect
			(at 0 -1.175004 90)
			(size 1.3716 4.5212)
			(layers "F.Cu" "F.Mask" "F.Paste")
			(net "IND_SOC_P1_CPL0")
		)
		(pad "3" smd rect
			(at 0 1.175004 90)
			(size 1.3716 4.5212)
			(layers "F.Cu" "F.Mask" "F.Paste")
			(net "IND_SOC_P1_CPL3")
		)
		(pad "4" smd rect
			(at 0 4.249928 90)
			(size 2.413 4.5212)
			(layers "F.Cu" "F.Mask" "F.Paste")
			(net "PVDDCR_SOC_P1")
		)
	)
	(footprint ""
		(layer "F.Cu")
		(at 72.2884 -382.27)
		(property "Reference" "R6717"
			(at 0 0 0)
			(layer "F.SilkS")
			(hide yes)
			(effects
				(font
					(size 1.27 1.27)
				)
			)
		)
		(property "Value" ""
			(at 0 0 0)
			(layer "F.Fab")
			(effects
				(font
					(size 1.27 1.27)
				)
			)
		)
		(duplicate_pad_numbers_are_jumpers no)
		(fp_line
			(start -0.32512 -0.175006)
			(end 0.32512 -0.175006)
			(stroke
				(width 0.1)
				(type default)
			)
			(layer "F.Fab")
		)
		(fp_line
			(start -0.32512 0.175006)
			(end -0.32512 -0.175006)
			(stroke
				(width 0.1)
				(type default)
			)
			(layer "F.Fab")
		)
		(fp_line
			(start 0.32512 -0.175006)
			(end 0.32512 0.175006)
			(stroke
				(width 0.1)
				(type default)
			)
			(layer "F.Fab")
		)
		(fp_line
			(start 0.32512 0.175006)
			(end -0.32512 0.175006)
			(stroke
				(width 0.1)
				(type default)
			)
			(layer "F.Fab")
		)
		(pad "1" smd rect
			(at -0.2667 0)
			(size 0.3048 0.381)
			(layers "F.Cu" "F.Mask" "F.Paste")
			(net "RT_CPU1_P0_ADDR1")
		)
		(pad "2" smd rect
			(at 0.2667 0 180)
			(size 0.3048 0.381)
			(layers "F.Cu" "F.Mask" "F.Paste")
			(net "GND")
		)
	)
	(footprint ""
		(layer "F.Cu")
		(at 120.995186 -408.517344 -90)
		(property "Reference" "C6698"
			(at 0 0 270)
			(layer "F.SilkS")
			(hide yes)
			(effects
				(font
					(size 1.27 1.27)
				)
			)
		)
		(property "Value" ""
			(at 0 0 270)
			(layer "F.Fab")
			(effects
				(font
					(size 1.27 1.27)
				)
			)
		)
		(duplicate_pad_numbers_are_jumpers no)
		(fp_line
			(start -0.299974 0.150114)
			(end -0.299974 -0.150114)
			(stroke
				(width 0.1)
				(type default)
			)
			(layer "F.Fab")
		)
		(fp_line
			(start 0.299974 0.150114)
			(end -0.299974 0.150114)
			(stroke
				(width 0.1)
				(type default)
			)
			(layer "F.Fab")
		)
		(fp_line
			(start -0.299974 -0.150114)
			(end 0.299974 -0.150114)
			(stroke
				(width 0.1)
				(type default)
			)
			(layer "F.Fab")
		)
		(fp_line
			(start 0.299974 -0.150114)
			(end 0.299974 0.150114)
			(stroke
				(width 0.1)
				(type default)
			)
			(layer "F.Fab")
		)
		(pad "1" smd rect
			(at -0.2667 0 270)
			(size 0.3048 0.381)
			(layers "F.Cu" "F.Mask" "F.Paste")
			(net "P5E_CPU1_P2_TX_BUF_C_DN<2>")
		)
		(pad "2" smd rect
			(at 0.2667 0 270)
			(size 0.3048 0.381)
			(layers "F.Cu" "F.Mask" "F.Paste")
			(net "P5E_CPU1_P2_TX_BUF_DN<2>")
		)
	)
	(footprint ""
		(layer "F.Cu")
		(at 178.985164 -129.366518 -90)
		(property "Reference" "R6710"
			(at 0 0 270)
			(layer "F.SilkS")
			(hide yes)
			(effects
				(font
					(size 1.27 1.27)
				)
			)
		)
		(property "Value" ""
			(at 0 0 270)
			(layer "F.Fab")
			(effects
				(font
					(size 1.27 1.27)
				)
			)
		)
		(duplicate_pad_numbers_are_jumpers no)
		(fp_line
			(start -0.7874 0.4064)
			(end -0.7874 -0.4064)
			(stroke
				(width 0.1524)
				(type default)
			)
			(layer "F.SilkS")
		)
		(fp_line
			(start 0.7874 0.4064)
			(end -0.7874 0.4064)
			(stroke
				(width 0.1524)
				(type default)
			)
			(layer "F.SilkS")
		)
		(fp_line
			(start -0.7874 -0.4064)
			(end 0.7874 -0.4064)
			(stroke
				(width 0.1524)
				(type default)
			)
			(layer "F.SilkS")
		)
		(fp_line
			(start 0.7874 -0.4064)
			(end 0.7874 0.4064)
			(stroke
				(width 0.1524)
				(type default)
			)
			(layer "F.SilkS")
		)
		(fp_line
			(start -0.67945 0.3048)
			(end -0.67945 -0.305054)
			(stroke
				(width 0.1)
				(type default)
			)
			(layer "F.Fab")
		)
		(fp_line
			(start -0.12065 0.3048)
			(end -0.67945 0.3048)
			(stroke
				(width 0.1)
				(type default)
			)
			(layer "F.Fab")
		)
		(fp_line
			(start 0.120396 0.3048)
			(end 0.120396 0.2794)
			(stroke
				(width 0.1)
				(type default)
			)
			(layer "F.Fab")
		)
		(fp_line
			(start 0.67945 0.3048)
			(end 0.120396 0.3048)
			(stroke
				(width 0.1)
				(type default)
			)
			(layer "F.Fab")
		)
		(fp_line
			(start -0.12065 0.2794)
			(end -0.12065 0.3048)
			(stroke
				(width 0.1)
				(type default)
			)
			(layer "F.Fab")
		)
		(fp_line
			(start 0.120396 0.2794)
			(end -0.12065 0.2794)
			(stroke
				(width 0.1)
				(type default)
			)
			(layer "F.Fab")
		)
		(fp_line
			(start -0.12065 -0.2794)
			(end 0.12065 -0.2794)
			(stroke
				(width 0.1)
				(type default)
			)
			(layer "F.Fab")
		)
		(fp_line
			(start 0.12065 -0.2794)
			(end 0.12065 -0.3048)
			(stroke
				(width 0.1)
				(type default)
			)
			(layer "F.Fab")
		)
		(fp_line
			(start 0.12065 -0.3048)
			(end 0.67945 -0.3048)
			(stroke
				(width 0.1)
				(type default)
			)
			(layer "F.Fab")
		)
		(fp_line
			(start 0.67945 -0.3048)
			(end 0.67945 0.3048)
			(stroke
				(width 0.1)
				(type default)
			)
			(layer "F.Fab")
		)
		(fp_line
			(start -0.67945 -0.305054)
			(end -0.12065 -0.305054)
			(stroke
				(width 0.1)
				(type default)
			)
			(layer "F.Fab")
		)
		(fp_line
			(start -0.12065 -0.305054)
			(end -0.12065 -0.2794)
			(stroke
				(width 0.1)
				(type default)
			)
			(layer "F.Fab")
		)
		(pad "1" smd circle
			(at -0.40005 0 270)
			(size 0 0)
			(layers "F.Cu" "F.Mask" "F.Paste")
			(net "RST_RT_CPU1_P0_PERST_R_N")
		)
		(pad "2" smd circle
			(at 0.40005 0 270)
			(size 0 0)
			(layers "F.Cu" "F.Mask" "F.Paste")
			(net "RST_RT_CPU1_P0_PERST_R2_N")
		)
	)
)
